(kicad_pcb
	(version 20241229)
	(generator "pcbnew")
	(generator_version "9.0")
	(general
		(thickness 1.63)
		(legacy_teardrops no)
	)
	(paper "A4")
	(title_block
		(title "CM4 Baseboard")
		(date "2026-01-05")
		(rev "1.1.1")
		(company "Antmicro Ltd")
		(comment 1 "www.antmicro.com")
		(comment 9 "footprints 431-436 of 506")
	)
	(layers
		(0 "F.Cu" signal)
		(4 "In1.Cu" power)
		(6 "In2.Cu" power)
		(8 "In3.Cu" signal)
		(10 "In4.Cu" signal)
		(2 "B.Cu" signal)
		(9 "F.Adhes" user "F.Adhesive")
		(11 "B.Adhes" user "B.Adhesive")
		(13 "F.Paste" user)
		(15 "B.Paste" user)
		(5 "F.SilkS" user "F.Silkscreen")
		(7 "B.SilkS" user "B.Silkscreen")
		(1 "F.Mask" user)
		(3 "B.Mask" user)
		(17 "Dwgs.User" user "User.Drawings")
		(19 "Cmts.User" user "User.Comments")
		(21 "Eco1.User" user "User.Eco1")
		(23 "Eco2.User" user "User.Eco2")
		(25 "Edge.Cuts" user)
		(27 "Margin" user)
		(31 "F.CrtYd" user "F.Courtyard")
		(29 "B.CrtYd" user "B.Courtyard")
		(35 "F.Fab" user)
		(33 "B.Fab" user)
	)
	(footprint "antmicro-footprints:R_0402_1005Metric"
		(layer "B.Cu")
		(at 80.817962 132.5165 180)
		(descr "Resistor SMD 0402")
		(tags "resistor SMD 0402")
		(property "Reference" "R911"
			(at -3.63 -0.41 0)
			(layer "B.SilkS")
			(effects
				(font
					(size 0.7 0.7)
					(thickness 0.15)
				)
				(justify left bottom mirror)
			)
		)
		(property "Value" "R_10k_0402"
			(at -1.011843 -1.772047 0)
			(layer "B.Fab")
			(effects
				(font
					(size 0.7 0.7)
					(thickness 0.15)
				)
				(justify left bottom mirror)
			)
		)
		(property "Datasheet" "https://www.bourns.com/docs/product-datasheets/cr.pdf"
			(at 0 0 180)
			(layer "B.Fab")
			(hide yes)
			(effects
				(font
					(size 1.27 1.27)
					(thickness 0.15)
				)
			)
		)
		(property "Manufacturer" "Bourns"
			(at 0 0 180)
			(unlocked yes)
			(layer "B.Fab")
			(hide yes)
			(effects
				(font
					(size 1 1)
					(thickness 0.15)
				)
				(justify mirror)
			)
		)
		(property "MPN" "CR0402-FX-1002GLF"
			(at 0 0 180)
			(unlocked yes)
			(layer "B.Fab")
			(hide yes)
			(effects
				(font
					(size 1 1)
					(thickness 0.15)
				)
				(justify mirror)
			)
		)
		(property "Val" "10k"
			(at 0 0 180)
			(unlocked yes)
			(layer "B.Fab")
			(hide yes)
			(effects
				(font
					(size 1 1)
					(thickness 0.15)
				)
				(justify mirror)
			)
		)
		(property "License" "Apache-2.0"
			(at 0 0 180)
			(unlocked yes)
			(layer "B.Fab")
			(hide yes)
			(effects
				(font
					(size 1 1)
					(thickness 0.15)
				)
				(justify mirror)
			)
		)
		(property "Author" "Antmicro"
			(at 0 0 180)
			(unlocked yes)
			(layer "B.Fab")
			(hide yes)
			(effects
				(font
					(size 1 1)
					(thickness 0.15)
				)
				(justify mirror)
			)
		)
		(property "Tolerance" "1%"
			(at 0 0 180)
			(unlocked yes)
			(layer "B.Fab")
			(hide yes)
			(effects
				(font
					(size 1 1)
					(thickness 0.15)
				)
				(justify mirror)
			)
		)
		(sheetname "/USB/")
		(sheetfile "usb.kicad_sch")
		(attr smd exclude_from_pos_files exclude_from_bom dnp)
		(fp_rect
			(start -0.925 0.47)
			(end 0.925 -0.47)
			(stroke
				(width 0.05)
				(type default)
			)
			(fill no)
			(layer "B.CrtYd")
		)
		(fp_rect
			(start -0.5 0.25)
			(end 0.5 -0.25)
			(stroke
				(width 0.15)
				(type solid)
			)
			(fill no)
			(layer "B.Fab")
		)
		(fp_text user "Author: Antmicro"
			(at -0.95 -4.169 0)
			(layer "B.Fab")
			(effects
				(font
					(size 0.7 0.7)
					(thickness 0.15)
				)
				(justify left bottom mirror)
			)
		)
		(fp_text user "${REFERENCE}"
			(at -0.95 -3.168 0)
			(layer "B.Fab")
			(effects
				(font
					(size 0.7 0.7)
					(thickness 0.15)
				)
				(justify left bottom mirror)
			)
		)
		(fp_text user "License: Apache-2.0"
			(at -0.95 -5.169 0)
			(layer "B.Fab")
			(effects
				(font
					(size 0.7 0.7)
					(thickness 0.15)
				)
				(justify left bottom mirror)
			)
		)
		(pad "1" smd roundrect
			(at -0.48 0 180)
			(size 0.59 0.64)
			(layers "B.Cu" "B.Mask" "B.Paste")
			(roundrect_rratio 0.25)
			(net 27 "/USB/USB_3V3")
			(pintype "passive")
		)
		(pad "2" smd roundrect
			(at 0.48 0 180)
			(size 0.59 0.64)
			(layers "B.Cu" "B.Mask" "B.Paste")
			(roundrect_rratio 0.25)
			(net 283 "/USB/EECS")
			(pintype "passive")
		)
	)
	(footprint "antmicro-footprints:R_0402_1005Metric"
		(layer "B.Cu")
		(at 41.857962 158.6385)
		(descr "Resistor SMD 0402")
		(tags "resistor SMD 0402")
		(property "Reference" "R309"
			(at -3.61 0.968 0)
			(layer "B.SilkS")
			(effects
				(font
					(size 0.7 0.7)
					(thickness 0.15)
				)
				(justify right bottom mirror)
			)
		)
		(property "Value" "R_4k7_0402"
			(at -1.011843 -1.772047 0)
			(layer "B.Fab")
			(effects
				(font
					(size 0.7 0.7)
					(thickness 0.15)
				)
				(justify right bottom mirror)
			)
		)
		(property "Datasheet" "https://www.bourns.com/docs/product-datasheets/cr.pdf"
			(at 0 0 0)
			(layer "B.Fab")
			(hide yes)
			(effects
				(font
					(size 1.27 1.27)
					(thickness 0.15)
				)
			)
		)
		(property "Manufacturer" "Bourns"
			(at 0 0 0)
			(unlocked yes)
			(layer "B.Fab")
			(hide yes)
			(effects
				(font
					(size 1 1)
					(thickness 0.15)
				)
				(justify mirror)
			)
		)
		(property "MPN" "CR0402-FX-4701GLF"
			(at 0 0 0)
			(unlocked yes)
			(layer "B.Fab")
			(hide yes)
			(effects
				(font
					(size 1 1)
					(thickness 0.15)
				)
				(justify mirror)
			)
		)
		(property "Val" "4k7"
			(at 0 0 0)
			(unlocked yes)
			(layer "B.Fab")
			(hide yes)
			(effects
				(font
					(size 1 1)
					(thickness 0.15)
				)
				(justify mirror)
			)
		)
		(property "License" "Apache-2.0"
			(at 0 0 0)
			(unlocked yes)
			(layer "B.Fab")
			(hide yes)
			(effects
				(font
					(size 1 1)
					(thickness 0.15)
				)
				(justify mirror)
			)
		)
		(property "Author" "Antmicro"
			(at 0 0 0)
			(unlocked yes)
			(layer "B.Fab")
			(hide yes)
			(effects
				(font
					(size 1 1)
					(thickness 0.15)
				)
				(justify mirror)
			)
		)
		(property "Tolerance" "1%"
			(at 0 0 0)
			(unlocked yes)
			(layer "B.Fab")
			(hide yes)
			(effects
				(font
					(size 1 1)
					(thickness 0.15)
				)
				(justify mirror)
			)
		)
		(sheetname "/Supply/")
		(sheetfile "supply.kicad_sch")
		(attr smd)
		(fp_rect
			(start -0.925 0.47)
			(end 0.925 -0.47)
			(stroke
				(width 0.05)
				(type default)
			)
			(fill no)
			(layer "B.CrtYd")
		)
		(fp_rect
			(start -0.5 0.25)
			(end 0.5 -0.25)
			(stroke
				(width 0.15)
				(type solid)
			)
			(fill no)
			(layer "B.Fab")
		)
		(fp_text user "License: Apache-2.0"
			(at -0.95 -5.169 180)
			(layer "B.Fab")
			(effects
				(font
					(size 0.7 0.7)
					(thickness 0.15)
				)
				(justify left bottom mirror)
			)
		)
		(fp_text user "${REFERENCE}"
			(at -0.95 -3.168 180)
			(layer "B.Fab")
			(effects
				(font
					(size 0.7 0.7)
					(thickness 0.15)
				)
				(justify left bottom mirror)
			)
		)
		(fp_text user "Author: Antmicro"
			(at -0.95 -4.169 180)
			(layer "B.Fab")
			(effects
				(font
					(size 0.7 0.7)
					(thickness 0.15)
				)
				(justify left bottom mirror)
			)
		)
		(pad "1" smd roundrect
			(at -0.48 0)
			(size 0.59 0.64)
			(layers "B.Cu" "B.Mask" "B.Paste")
			(roundrect_rratio 0.25)
			(net 3 "GND")
			(pintype "passive")
		)
		(pad "2" smd roundrect
			(at 0.48 0)
			(size 0.59 0.64)
			(layers "B.Cu" "B.Mask" "B.Paste")
			(roundrect_rratio 0.25)
			(net 17 "Net-(Q307-G)")
			(pintype "passive")
		)
	)
	(footprint "antmicro-footprints:C_0402_1005Metric"
		(layer "B.Cu")
		(at 119.142962 129.7665 -90)
		(descr "Capacitor SMD 0402")
		(tags "capacitor SMD 0402")
		(property "Reference" "C504"
			(at -4.01 -0.535 90)
			(layer "B.SilkS")
			(effects
				(font
					(size 0.7 0.7)
					(thickness 0.15)
				)
				(justify left bottom mirror)
			)
		)
		(property "Value" "C_1u_0402"
			(at -1.022927 -2.155213 90)
			(layer "B.Fab")
			(effects
				(font
					(size 0.7 0.7)
					(thickness 0.15)
				)
				(justify left bottom mirror)
			)
		)
		(property "Datasheet" "https://product.tdk.com/en/search/capacitor/ceramic/mlcc/info?part_no=C1005X6S1A105K050BC"
			(at 0 0 270)
			(layer "B.Fab")
			(hide yes)
			(effects
				(font
					(size 1.27 1.27)
					(thickness 0.15)
				)
			)
		)
		(property "Manufacturer" "TDK"
			(at 0 0 270)
			(unlocked yes)
			(layer "B.Fab")
			(hide yes)
			(effects
				(font
					(size 1 1)
					(thickness 0.15)
				)
				(justify mirror)
			)
		)
		(property "MPN" "C1005X6S1A105K050BC"
			(at 0 0 270)
			(unlocked yes)
			(layer "B.Fab")
			(hide yes)
			(effects
				(font
					(size 1 1)
					(thickness 0.15)
				)
				(justify mirror)
			)
		)
		(property "Val" "1u"
			(at 0 0 270)
			(unlocked yes)
			(layer "B.Fab")
			(hide yes)
			(effects
				(font
					(size 1 1)
					(thickness 0.15)
				)
				(justify mirror)
			)
		)
		(property "License" "Apache-2.0"
			(at 0 0 270)
			(unlocked yes)
			(layer "B.Fab")
			(hide yes)
			(effects
				(font
					(size 1 1)
					(thickness 0.15)
				)
				(justify mirror)
			)
		)
		(property "Author" "Antmicro"
			(at 0 0 270)
			(unlocked yes)
			(layer "B.Fab")
			(hide yes)
			(effects
				(font
					(size 1 1)
					(thickness 0.15)
				)
				(justify mirror)
			)
		)
		(property "Voltage" ""
			(at 0 0 270)
			(unlocked yes)
			(layer "B.Fab")
			(hide yes)
			(effects
				(font
					(size 1 1)
					(thickness 0.15)
				)
				(justify mirror)
			)
		)
		(property "Dielectric" ""
			(at 0 0 270)
			(unlocked yes)
			(layer "B.Fab")
			(hide yes)
			(effects
				(font
					(size 1 1)
					(thickness 0.15)
				)
				(justify mirror)
			)
		)
		(sheetname "/NVMe & microSD/")
		(sheetfile "nvme-micro-sd.kicad_sch")
		(attr smd)
		(fp_rect
			(start -0.925 0.47)
			(end 0.925 -0.47)
			(stroke
				(width 0.05)
				(type default)
			)
			(fill no)
			(layer "B.CrtYd")
		)
		(fp_line
			(start -0.494 0.25)
			(end 0.504 0.25)
			(stroke
				(width 0.15)
				(type solid)
			)
			(layer "B.Fab")
		)
		(fp_line
			(start 0.504 0.25)
			(end 0.504 -0.248)
			(stroke
				(width 0.15)
				(type solid)
			)
			(layer "B.Fab")
		)
		(fp_line
			(start -0.494 -0.248)
			(end -0.494 0.25)
			(stroke
				(width 0.15)
				(type solid)
			)
			(layer "B.Fab")
		)
		(fp_line
			(start 0.504 -0.248)
			(end -0.494 -0.248)
			(stroke
				(width 0.15)
				(type solid)
			)
			(layer "B.Fab")
		)
		(fp_text user "License: Apache-2.0"
			(at -0.939 -5.799 90)
			(layer "B.Fab")
			(effects
				(font
					(size 0.7 0.7)
					(thickness 0.15)
				)
				(justify left bottom mirror)
			)
		)
		(fp_text user "Author: Antmicro"
			(at -0.939 -3.399 90)
			(layer "B.Fab")
			(effects
				(font
					(size 0.7 0.7)
					(thickness 0.15)
				)
				(justify left bottom mirror)
			)
		)
		(fp_text user "${REFERENCE}"
			(at -0.939 -4.599 90)
			(layer "B.Fab")
			(effects
				(font
					(size 0.7 0.7)
					(thickness 0.15)
				)
				(justify left bottom mirror)
			)
		)
		(pad "1" smd roundrect
			(at -0.48 0 270)
			(size 0.59 0.64)
			(layers "B.Cu" "B.Mask" "B.Paste")
			(roundrect_rratio 0.25)
			(net 3 "GND")
			(pintype "passive")
		)
		(pad "2" smd roundrect
			(at 0.48 0 270)
			(size 0.59 0.64)
			(layers "B.Cu" "B.Mask" "B.Paste")
			(roundrect_rratio 0.25)
			(net 65 "3V3_SSD")
			(pintype "passive")
		)
	)
	(footprint "antmicro-footprints:TP_SMD_0.75mm"
		(layer "B.Cu")
		(at 83.5 136 180)
		(property "Reference" "TP906"
			(at -3.045 0.52 0)
			(layer "B.SilkS")
			(effects
				(font
					(size 0.7 0.7)
					(thickness 0.15)
				)
				(justify left bottom mirror)
			)
		)
		(property "Value" "TP_0.75mm_SMD"
			(at 0 -1.2 0)
			(layer "B.Fab")
			(effects
				(font
					(size 0.7 0.7)
					(thickness 0.15)
				)
				(justify left bottom mirror)
			)
		)
		(property "MPN" ""
			(at 0 0 180)
			(unlocked yes)
			(layer "B.Fab")
			(hide yes)
			(effects
				(font
					(size 1 1)
					(thickness 0.15)
				)
				(justify mirror)
			)
		)
		(property "Manufacturer" ""
			(at 0 0 180)
			(unlocked yes)
			(layer "B.Fab")
			(hide yes)
			(effects
				(font
					(size 1 1)
					(thickness 0.15)
				)
				(justify mirror)
			)
		)
		(property "Author" "Antmicro"
			(at 0 0 180)
			(unlocked yes)
			(layer "B.Fab")
			(hide yes)
			(effects
				(font
					(size 1 1)
					(thickness 0.15)
				)
				(justify mirror)
			)
		)
		(property "License" "Apache-2.0"
			(at 0 0 180)
			(unlocked yes)
			(layer "B.Fab")
			(hide yes)
			(effects
				(font
					(size 1 1)
					(thickness 0.15)
				)
				(justify mirror)
			)
		)
		(sheetname "/USB/")
		(sheetfile "usb.kicad_sch")
		(attr exclude_from_pos_files exclude_from_bom)
		(fp_circle
			(center 0 0)
			(end 0.475 0)
			(stroke
				(width 0.05)
				(type default)
			)
			(fill no)
			(layer "B.CrtYd")
		)
		(fp_text user "Author: Antmicro"
			(at -0.4 -3.901 0)
			(layer "B.Fab")
			(effects
				(font
					(size 0.7 0.7)
					(thickness 0.15)
				)
				(justify left bottom mirror)
			)
		)
		(fp_text user "${REFERENCE}"
			(at -0.4 -2.7 0)
			(layer "B.Fab")
			(effects
				(font
					(size 0.7 0.7)
					(thickness 0.15)
				)
				(justify left bottom mirror)
			)
		)
		(fp_text user "License: Apache-2.0"
			(at -0.4 -5.101 0)
			(layer "B.Fab")
			(effects
				(font
					(size 0.7 0.7)
					(thickness 0.15)
				)
				(justify left bottom mirror)
			)
		)
		(pad "1" smd circle
			(at 0 0 180)
			(size 0.75 0.75)
			(layers "B.Cu" "B.Mask")
			(net 379 "Net-(U905-~{RESET})")
			(pinfunction "1")
			(pintype "passive")
		)
	)
	(footprint "antmicro-footprints:R_0402_1005Metric"
		(layer "B.Cu")
		(at 81.292962 135.5415 -90)
		(descr "Resistor SMD 0402")
		(tags "resistor SMD 0402")
		(property "Reference" "R906"
			(at 0.655 -0.415 90)
			(layer "B.SilkS")
			(effects
				(font
					(size 0.7 0.7)
					(thickness 0.15)
				)
				(justify left bottom mirror)
			)
		)
		(property "Value" "R_10k_0402"
			(at -1.011843 -1.772047 90)
			(layer "B.Fab")
			(effects
				(font
					(size 0.7 0.7)
					(thickness 0.15)
				)
				(justify left bottom mirror)
			)
		)
		(property "Datasheet" "https://www.bourns.com/docs/product-datasheets/cr.pdf"
			(at 0 0 270)
			(layer "B.Fab")
			(hide yes)
			(effects
				(font
					(size 1.27 1.27)
					(thickness 0.15)
				)
			)
		)
		(property "Manufacturer" "Bourns"
			(at 0 0 270)
			(unlocked yes)
			(layer "B.Fab")
			(hide yes)
			(effects
				(font
					(size 1 1)
					(thickness 0.15)
				)
				(justify mirror)
			)
		)
		(property "MPN" "CR0402-FX-1002GLF"
			(at 0 0 270)
			(unlocked yes)
			(layer "B.Fab")
			(hide yes)
			(effects
				(font
					(size 1 1)
					(thickness 0.15)
				)
				(justify mirror)
			)
		)
		(property "Val" "10k"
			(at 0 0 270)
			(unlocked yes)
			(layer "B.Fab")
			(hide yes)
			(effects
				(font
					(size 1 1)
					(thickness 0.15)
				)
				(justify mirror)
			)
		)
		(property "License" "Apache-2.0"
			(at 0 0 270)
			(unlocked yes)
			(layer "B.Fab")
			(hide yes)
			(effects
				(font
					(size 1 1)
					(thickness 0.15)
				)
				(justify mirror)
			)
		)
		(property "Author" "Antmicro"
			(at 0 0 270)
			(unlocked yes)
			(layer "B.Fab")
			(hide yes)
			(effects
				(font
					(size 1 1)
					(thickness 0.15)
				)
				(justify mirror)
			)
		)
		(property "Tolerance" "1%"
			(at 0 0 270)
			(unlocked yes)
			(layer "B.Fab")
			(hide yes)
			(effects
				(font
					(size 1 1)
					(thickness 0.15)
				)
				(justify mirror)
			)
		)
		(sheetname "/USB/")
		(sheetfile "usb.kicad_sch")
		(attr smd)
		(fp_rect
			(start -0.925 0.47)
			(end 0.925 -0.47)
			(stroke
				(width 0.05)
				(type default)
			)
			(fill no)
			(layer "B.CrtYd")
		)
		(fp_rect
			(start -0.5 0.25)
			(end 0.5 -0.25)
			(stroke
				(width 0.15)
				(type solid)
			)
			(fill no)
			(layer "B.Fab")
		)
		(fp_text user "Author: Antmicro"
			(at -0.95 -4.169 90)
			(layer "B.Fab")
			(effects
				(font
					(size 0.7 0.7)
					(thickness 0.15)
				)
				(justify left bottom mirror)
			)
		)
		(fp_text user "${REFERENCE}"
			(at -0.95 -3.168 90)
			(layer "B.Fab")
			(effects
				(font
					(size 0.7 0.7)
					(thickness 0.15)
				)
				(justify left bottom mirror)
			)
		)
		(fp_text user "License: Apache-2.0"
			(at -0.95 -5.169 90)
			(layer "B.Fab")
			(effects
				(font
					(size 0.7 0.7)
					(thickness 0.15)
				)
				(justify left bottom mirror)
			)
		)
		(pad "1" smd roundrect
			(at -0.48 0 270)
			(size 0.59 0.64)
			(layers "B.Cu" "B.Mask" "B.Paste")
			(roundrect_rratio 0.25)
			(net 27 "/USB/USB_3V3")
			(pintype "passive")
		)
		(pad "2" smd roundrect
			(at 0.48 0 270)
			(size 0.59 0.64)
			(layers "B.Cu" "B.Mask" "B.Paste")
			(roundrect_rratio 0.25)
			(net 377 "Net-(U902-DO)")
			(pintype "passive")
		)
	)
	(footprint "antmicro-footprints:C_0402_1005Metric"
		(layer "B.Cu")
		(at 118.117962 115.7665 -90)
		(descr "Capacitor SMD 0402")
		(tags "capacitor SMD 0402")
		(property "Reference" "C505"
			(at 1.33 1.88 90)
			(layer "B.SilkS")
			(effects
				(font
					(size 0.7 0.7)
					(thickness 0.15)
				)
				(justify left bottom mirror)
			)
		)
		(property "Value" "C_10u_0402"
			(at -1.022927 -2.155213 90)
			(layer "B.Fab")
			(effects
				(font
					(size 0.7 0.7)
					(thickness 0.15)
				)
				(justify left bottom mirror)
			)
		)
		(property "Datasheet" "https://www.yageo.com/en/Chart/Download/pdf/CC0402MRX5R5BB106"
			(at 0 0 270)
			(layer "B.Fab")
			(hide yes)
			(effects
				(font
					(size 1.27 1.27)
					(thickness 0.15)
				)
			)
		)
		(property "MPN" "CC0402MRX5R5BB106"
			(at 0 0 270)
			(unlocked yes)
			(layer "B.Fab")
			(hide yes)
			(effects
				(font
					(size 1 1)
					(thickness 0.15)
				)
				(justify mirror)
			)
		)
		(property "Manufacturer" "YAGEO"
			(at 0 0 270)
			(unlocked yes)
			(layer "B.Fab")
			(hide yes)
			(effects
				(font
					(size 1 1)
					(thickness 0.15)
				)
				(justify mirror)
			)
		)
		(property "License" "Apache-2.0"
			(at 0 0 270)
			(unlocked yes)
			(layer "B.Fab")
			(hide yes)
			(effects
				(font
					(size 1 1)
					(thickness 0.15)
				)
				(justify mirror)
			)
		)
		(property "Author" "Antmicro"
			(at 0 0 270)
			(unlocked yes)
			(layer "B.Fab")
			(hide yes)
			(effects
				(font
					(size 1 1)
					(thickness 0.15)
				)
				(justify mirror)
			)
		)
		(property "Val" "10u"
			(at 0 0 270)
			(unlocked yes)
			(layer "B.Fab")
			(hide yes)
			(effects
				(font
					(size 1 1)
					(thickness 0.15)
				)
				(justify mirror)
			)
		)
		(property "Voltage" ""
			(at 0 0 270)
			(unlocked yes)
			(layer "B.Fab")
			(hide yes)
			(effects
				(font
					(size 1 1)
					(thickness 0.15)
				)
				(justify mirror)
			)
		)
		(property "Dielectric" ""
			(at 0 0 270)
			(unlocked yes)
			(layer "B.Fab")
			(hide yes)
			(effects
				(font
					(size 1 1)
					(thickness 0.15)
				)
				(justify mirror)
			)
		)
		(sheetname "/NVMe & microSD/")
		(sheetfile "nvme-micro-sd.kicad_sch")
		(attr smd)
		(fp_rect
			(start -0.925 0.47)
			(end 0.925 -0.47)
			(stroke
				(width 0.05)
				(type default)
			)
			(fill no)
			(layer "B.CrtYd")
		)
		(fp_line
			(start -0.494 0.25)
			(end 0.504 0.25)
			(stroke
				(width 0.15)
				(type solid)
			)
			(layer "B.Fab")
		)
		(fp_line
			(start 0.504 0.25)
			(end 0.504 -0.248)
			(stroke
				(width 0.15)
				(type solid)
			)
			(layer "B.Fab")
		)
		(fp_line
			(start -0.494 -0.248)
			(end -0.494 0.25)
			(stroke
				(width 0.15)
				(type solid)
			)
			(layer "B.Fab")
		)
		(fp_line
			(start 0.504 -0.248)
			(end -0.494 -0.248)
			(stroke
				(width 0.15)
				(type solid)
			)
			(layer "B.Fab")
		)
		(fp_text user "${REFERENCE}"
			(at -0.939 -4.599 90)
			(layer "B.Fab")
			(effects
				(font
					(size 0.7 0.7)
					(thickness 0.15)
				)
				(justify left bottom mirror)
			)
		)
		(fp_text user "Author: Antmicro"
			(at -0.939 -3.399 90)
			(layer "B.Fab")
			(effects
				(font
					(size 0.7 0.7)
					(thickness 0.15)
				)
				(justify left bottom mirror)
			)
		)
		(fp_text user "License: Apache-2.0"
			(at -0.939 -5.799 90)
			(layer "B.Fab")
			(effects
				(font
					(size 0.7 0.7)
					(thickness 0.15)
				)
				(justify left bottom mirror)
			)
		)
		(pad "1" smd roundrect
			(at -0.48 0 270)
			(size 0.59 0.64)
			(layers "B.Cu" "B.Mask" "B.Paste")
			(roundrect_rratio 0.25)
			(net 3 "GND")
			(pintype "passive")
		)
		(pad "2" smd roundrect
			(at 0.48 0 270)
			(size 0.59 0.64)
			(layers "B.Cu" "B.Mask" "B.Paste")
			(roundrect_rratio 0.25)
			(net 65 "3V3_SSD")
			(pintype "passive")
		)
	)
)
